#ISCELL
  mstr_misc dns *
  *
#ISCELL
  mstr_symbols design_note *
  *
#ISCELL
  mstr_symbols intel_corp_bpage *
  *
#CELL
  mstr_discrete res *
  page211_i100
#CELL
  mstr_discrete res *
  page211_i102
#CELL
  dev_discrete cap_a *
  page211_i103
#CELL
  dev_discrete cap_a *
  page211_i11
#ISCELL
  mstr_symbols gnd *
  page211_i12
#CELL
  dev_discrete cap_a *
  page211_i13
#ISCELL
  mstr_symbols gnd *
  page211_i14
#ISCELL
  mstr_standard offpage *
  page211_i15
#CELL
  mstr_discrete res *
  page211_i16
#ISCELL
  mstr_symbols pvccio_cpu0 *
  page211_i18
#ISCELL
  mstr_standard offpage *
  page211_i19
#ISCELL
  mstr_symbols gnd *
  page211_i2
#CELL
  dev_discrete cap_a *
  page211_i20
#ISCELL
  mstr_symbols gnd *
  page211_i21
#CELL
  dev_discrete cap_a *
  page211_i22
#ISCELL
  mstr_symbols gnd *
  page211_i23
#CELL
  mstr_discrete res *
  page211_i24
#ISCELL
  mstr_symbols p3v3_stby *
  page211_i25
#ISCELL
  mstr_standard offpage *
  page211_i26
#ISCELL
  mstr_symbols pvccio_cpu0 *
  page211_i27
#CELL
  mstr_discrete res *
  page211_i29
#ISCELL
  mstr_standard offpage *
  page211_i3
#ISCELL
  mstr_symbols vcc_core *
  page211_i30
#CELL
  mstr_discrete res *
  page211_i31
#CELL
  mstr_discrete res *
  page211_i32
#ISCELL
  mstr_symbols gnd *
  page211_i34
#ISCELL
  mstr_symbols gnd *
  page211_i35
#ISCELL
  mstr_standard offpage *
  page211_i36
#ISCELL
  mstr_standard offpage *
  page211_i37
#ISCELL
  mstr_standard offpage *
  page211_i39
#ISCELL
  mstr_standard offpage *
  page211_i40
#ISCELL
  mstr_standard offpage *
  page211_i42
#ISCELL
  mstr_standard offpage *
  page211_i43
#ISCELL
  mstr_standard offpage *
  page211_i48
#ISCELL
  mstr_standard offpage *
  page211_i49
#ISCELL
  mstr_symbols gnd *
  page211_i51
#CELL
  mstr_discrete res *
  page211_i52
#ISCELL
  mstr_symbols gnd *
  page211_i54
#CELL
  mstr_discrete res *
  page211_i56
#ISCELL
  mstr_standard offpage *
  page211_i57
#CELL
  mstr_discrete res *
  page211_i58
#ISCELL
  mstr_symbols p3v3_stby *
  page211_i59
#ISCELL
  mstr_standard offpage *
  page211_i6
#CELL
  mstr_discrete res *
  page211_i60
#CELL
  mstr_discrete res *
  page211_i61
#ISCELL
  mstr_standard offpage *
  page211_i62
#CELL
  mstr_discrete res *
  page211_i64
#CELL
  mstr_discrete cap *
  page211_i71
#ISCELL
  mstr_symbols gnd *
  page211_i72
#CELL
  mstr_discrete res *
  page211_i81
#ISCELL
  mstr_standard offpage *
  page211_i82
#CELL
  mstr_discrete cap *
  page211_i83
#ISCELL
  mstr_standard offpage *
  page211_i84
#CELL
  mstr_discrete res *
  page211_i87
#CELL
  mstr_discrete res *
  page211_i88
#CELL
  mstr_controller pxe1110b *
  page211_i93
#CELL
  w_hdl sc22p50v2jn-4gp *
  page211_i95
#CELL
  mstr_discrete res *
  page211_i96
#CELL
  mstr_discrete cap *
  page211_i97
#ISCELL
  mstr_symbols gnd *
  page211_i98
#CELL
  mstr_discrete res *
  page211_i99
